# T6G (Grand Teton) — schematic netlist excerpt (pin names and nets, part order shuffled) for the footprints in the layout excerpt that follows; sources: Cadence DE-HDL packaged netlist, KiCad conversion of 04192023_DAF0TMB3IC0_F0TG_MB_C_brd_V02_OCP.brd

R4515  Q_RES  100K 1% CHIP  pkg 0402LF  page 130 : A = P3V3_AUX ; B = UART_BMC_BIC_RX
PR162  Q_RES  49.9 1% CHIP  pkg 0402LF  page 210 : A = VSENSE_VSS_SENSE_A_P1 ; B = GND

(kicad_pcb
	(version 20260206)
	(generator "pcbnew")
	(generator_version "10.0")
	(general
		(thickness 1.6)
		(legacy_teardrops no)
	)
	(paper "A4")
	(title_block
		(title "04192023_DAF0TMB3IC0_F0TG_MB_C_brd_V02_OCP.brd")
		(comment 1 "Grand Teton / footprints 3636-3637 of 8354")
	)
	(layers
		(0 "F.Cu" signal "TOP")
		(4 "In1.Cu" signal "GND")
		(6 "In2.Cu" signal "IN1")
		(8 "In3.Cu" signal "GND1")
		(10 "In4.Cu" signal "IN2")
		(12 "In5.Cu" signal "GND2")
		(14 "In6.Cu" signal "IN3")
		(16 "In7.Cu" signal "GND3")
		(18 "In8.Cu" signal "VCC")
		(20 "In9.Cu" signal "VCC1")
		(22 "In10.Cu" signal "GND4")
		(24 "In11.Cu" signal "IN4")
		(26 "In12.Cu" signal "GND5")
		(28 "In13.Cu" signal "IN5")
		(30 "In14.Cu" signal "GND6")
		(32 "In15.Cu" signal "IN6")
		(34 "In16.Cu" signal "GND7")
		(2 "B.Cu" signal "BOTTOM")
		(9 "F.Adhes" user "F.Adhesive")
		(11 "B.Adhes" user "B.Adhesive")
		(13 "F.Paste" user "Package Geometry/Pastemask Top")
		(15 "B.Paste" user "Package Geometry/Pastemask Bottom")
		(5 "F.SilkS" user "Ref Des/Silkscreen Top")
		(7 "B.SilkS" user "Ref Des/Silkscreen Bottom")
		(1 "F.Mask" user "Board Geometry/Soldermask Top")
		(3 "B.Mask" user "Board Geometry/Soldermask Bottom")
		(17 "Dwgs.User" user "User.Drawings")
		(19 "Cmts.User" user "User.Comments")
		(21 "Eco1.User" user "User.Eco1")
		(23 "Eco2.User" user "User.Eco2")
		(25 "Edge.Cuts" user "Board Geometry/Outline")
		(27 "Margin" user)
		(31 "F.CrtYd" user "Package Geometry/Place Bound Top")
		(29 "B.CrtYd" user "Package Geometry/Place Bound Bottom")
		(35 "F.Fab" user "Ref Des/Assembly Top")
		(33 "B.Fab" user "Ref Des/Assembly Bottom")
	)
	(footprint ""
		(layer "F.Cu")
		(at 59.508644 -180.746908)
		(property "Reference" "PR162"
			(at 0 0 0)
			(layer "F.SilkS")
			(hide yes)
			(effects
				(font
					(size 1.27 1.27)
				)
			)
		)
		(property "Value" ""
			(at 0 0 0)
			(layer "F.Fab")
			(effects
				(font
					(size 1.27 1.27)
				)
			)
		)
		(duplicate_pad_numbers_are_jumpers no)
		(fp_line
			(start -0.7874 -0.4064)
			(end 0.7874 -0.4064)
			(stroke
				(width 0.1524)
				(type default)
			)
			(layer "F.SilkS")
		)
		(fp_line
			(start -0.7874 0.4064)
			(end -0.7874 -0.4064)
			(stroke
				(width 0.1524)
				(type default)
			)
			(layer "F.SilkS")
		)
		(fp_line
			(start 0.7874 -0.4064)
			(end 0.7874 0.4064)
			(stroke
				(width 0.1524)
				(type default)
			)
			(layer "F.SilkS")
		)
		(fp_line
			(start 0.7874 0.4064)
			(end -0.7874 0.4064)
			(stroke
				(width 0.1524)
				(type default)
			)
			(layer "F.SilkS")
		)
		(fp_line
			(start -0.67945 -0.305054)
			(end -0.12065 -0.305054)
			(stroke
				(width 0.1)
				(type default)
			)
			(layer "F.Fab")
		)
		(fp_line
			(start -0.67945 0.3048)
			(end -0.67945 -0.305054)
			(stroke
				(width 0.1)
				(type default)
			)
			(layer "F.Fab")
		)
		(fp_line
			(start -0.12065 -0.305054)
			(end -0.12065 -0.2794)
			(stroke
				(width 0.1)
				(type default)
			)
			(layer "F.Fab")
		)
		(fp_line
			(start -0.12065 -0.2794)
			(end 0.12065 -0.2794)
			(stroke
				(width 0.1)
				(type default)
			)
			(layer "F.Fab")
		)
		(fp_line
			(start -0.12065 0.2794)
			(end -0.12065 0.3048)
			(stroke
				(width 0.1)
				(type default)
			)
			(layer "F.Fab")
		)
		(fp_line
			(start -0.12065 0.3048)
			(end -0.67945 0.3048)
			(stroke
				(width 0.1)
				(type default)
			)
			(layer "F.Fab")
		)
		(fp_line
			(start 0.120396 0.2794)
			(end -0.12065 0.2794)
			(stroke
				(width 0.1)
				(type default)
			)
			(layer "F.Fab")
		)
		(fp_line
			(start 0.120396 0.3048)
			(end 0.120396 0.2794)
			(stroke
				(width 0.1)
				(type default)
			)
			(layer "F.Fab")
		)
		(fp_line
			(start 0.12065 -0.3048)
			(end 0.67945 -0.3048)
			(stroke
				(width 0.1)
				(type default)
			)
			(layer "F.Fab")
		)
		(fp_line
			(start 0.12065 -0.2794)
			(end 0.12065 -0.3048)
			(stroke
				(width 0.1)
				(type default)
			)
			(layer "F.Fab")
		)
		(fp_line
			(start 0.67945 -0.3048)
			(end 0.67945 0.3048)
			(stroke
				(width 0.1)
				(type default)
			)
			(layer "F.Fab")
		)
		(fp_line
			(start 0.67945 0.3048)
			(end 0.120396 0.3048)
			(stroke
				(width 0.1)
				(type default)
			)
			(layer "F.Fab")
		)
		(pad "1" smd circle
			(at -0.40005 0)
			(size 0 0)
			(layers "F.Cu" "F.Mask" "F.Paste")
			(net "VSENSE_VSS_SENSE_A_P1")
		)
		(pad "2" smd circle
			(at 0.40005 0)
			(size 0 0)
			(layers "F.Cu" "F.Mask" "F.Paste")
			(net "GND")
		)
	)
	(footprint ""
		(layer "F.Cu")
		(at 360.583988 -409.388818 -90)
		(property "Reference" "R4515"
			(at 0 0 270)
			(layer "F.SilkS")
			(hide yes)
			(effects
				(font
					(size 1.27 1.27)
				)
			)
		)
		(property "Value" ""
			(at 0 0 270)
			(layer "F.Fab")
			(effects
				(font
					(size 1.27 1.27)
				)
			)
		)
		(duplicate_pad_numbers_are_jumpers no)
		(fp_line
			(start -0.7874 0.4064)
			(end -0.7874 -0.4064)
			(stroke
				(width 0.1524)
				(type default)
			)
			(layer "F.SilkS")
		)
		(fp_line
			(start 0.7874 0.4064)
			(end -0.7874 0.4064)
			(stroke
				(width 0.1524)
				(type default)
			)
			(layer "F.SilkS")
		)
		(fp_line
			(start -0.7874 -0.4064)
			(end 0.7874 -0.4064)
			(stroke
				(width 0.1524)
				(type default)
			)
			(layer "F.SilkS")
		)
		(fp_line
			(start 0.7874 -0.4064)
			(end 0.7874 0.4064)
			(stroke
				(width 0.1524)
				(type default)
			)
			(layer "F.SilkS")
		)
		(fp_line
			(start -0.67945 0.3048)
			(end -0.67945 -0.305054)
			(stroke
				(width 0.1)
				(type default)
			)
			(layer "F.Fab")
		)
		(fp_line
			(start -0.12065 0.3048)
			(end -0.67945 0.3048)
			(stroke
				(width 0.1)
				(type default)
			)
			(layer "F.Fab")
		)
		(fp_line
			(start 0.120396 0.3048)
			(end 0.120396 0.2794)
			(stroke
				(width 0.1)
				(type default)
			)
			(layer "F.Fab")
		)
		(fp_line
			(start 0.67945 0.3048)
			(end 0.120396 0.3048)
			(stroke
				(width 0.1)
				(type default)
			)
			(layer "F.Fab")
		)
		(fp_line
			(start -0.12065 0.2794)
			(end -0.12065 0.3048)
			(stroke
				(width 0.1)
				(type default)
			)
			(layer "F.Fab")
		)
		(fp_line
			(start 0.120396 0.2794)
			(end -0.12065 0.2794)
			(stroke
				(width 0.1)
				(type default)
			)
			(layer "F.Fab")
		)
		(fp_line
			(start -0.12065 -0.2794)
			(end 0.12065 -0.2794)
			(stroke
				(width 0.1)
				(type default)
			)
			(layer "F.Fab")
		)
		(fp_line
			(start 0.12065 -0.2794)
			(end 0.12065 -0.3048)
			(stroke
				(width 0.1)
				(type default)
			)
			(layer "F.Fab")
		)
		(fp_line
			(start 0.12065 -0.3048)
			(end 0.67945 -0.3048)
			(stroke
				(width 0.1)
				(type default)
			)
			(layer "F.Fab")
		)
		(fp_line
			(start 0.67945 -0.3048)
			(end 0.67945 0.3048)
			(stroke
				(width 0.1)
				(type default)
			)
			(layer "F.Fab")
		)
		(fp_line
			(start -0.67945 -0.305054)
			(end -0.12065 -0.305054)
			(stroke
				(width 0.1)
				(type default)
			)
			(layer "F.Fab")
		)
		(fp_line
			(start -0.12065 -0.305054)
			(end -0.12065 -0.2794)
			(stroke
				(width 0.1)
				(type default)
			)
			(layer "F.Fab")
		)
		(pad "1" smd circle
			(at -0.40005 0 270)
			(size 0 0)
			(layers "F.Cu" "F.Mask" "F.Paste")
			(net "P3V3_AUX")
		)
		(pad "2" smd circle
			(at 0.40005 0 270)
			(size 0 0)
			(layers "F.Cu" "F.Mask" "F.Paste")
			(net "UART_BMC_BIC_RX")
		)
	)
)
